(kicad_pcb
	(version 20260206)
	(generator "pcbnew")
	(generator_version "10.0")
	(general
		(thickness 1.6)
		(legacy_teardrops no)
	)
	(paper "A4")
	(title_block
		(title "12092022_DA0F0TFB6D0_F0T_FAN_BOARD_MP5048_D_brd_v02_OCP.brd")
		(comment 1 "Grand Teton / footprints 529-534 of 924")
	)
	(layers
		(0 "F.Cu" signal "TOP")
		(4 "In1.Cu" signal "GND")
		(6 "In2.Cu" signal "IN1")
		(8 "In3.Cu" signal "IN2")
		(10 "In4.Cu" signal "GND1")
		(2 "B.Cu" signal "BOTTOM")
		(9 "F.Adhes" user "F.Adhesive")
		(11 "B.Adhes" user "B.Adhesive")
		(13 "F.Paste" user "Package Geometry/Pastemask Top")
		(15 "B.Paste" user "Package Geometry/Pastemask Bottom")
		(5 "F.SilkS" user "Ref Des/Silkscreen Top")
		(7 "B.SilkS" user "Ref Des/Silkscreen Bottom")
		(1 "F.Mask" user "Board Geometry/Soldermask Top")
		(3 "B.Mask" user "Board Geometry/Soldermask Bottom")
		(17 "Dwgs.User" user "User.Drawings")
		(19 "Cmts.User" user "User.Comments")
		(21 "Eco1.User" user "User.Eco1")
		(23 "Eco2.User" user "User.Eco2")
		(25 "Edge.Cuts" user "Board Geometry/Outline")
		(27 "Margin" user)
		(31 "F.CrtYd" user "Package Geometry/Place Bound Top")
		(29 "B.CrtYd" user "Package Geometry/Place Bound Bottom")
		(35 "F.Fab" user "Ref Des/Assembly Top")
		(33 "B.Fab" user "Ref Des/Assembly Bottom")
	)
	(footprint ""
		(layer "F.Cu")
		(at 4.191 -163.957 180)
		(property "Reference" "R103"
			(at 0 0 180)
			(layer "F.SilkS")
			(hide yes)
			(effects
				(font
					(size 1.27 1.27)
				)
			)
		)
		(property "Value" ""
			(at 0 0 180)
			(layer "F.Fab")
			(effects
				(font
					(size 1.27 1.27)
				)
			)
		)
		(duplicate_pad_numbers_are_jumpers no)
		(fp_line
			(start 0.7874 0.4064)
			(end -0.7874 0.4064)
			(stroke
				(width 0.1524)
				(type default)
			)
			(layer "F.SilkS")
		)
		(fp_line
			(start 0.7874 -0.4064)
			(end 0.7874 0.4064)
			(stroke
				(width 0.1524)
				(type default)
			)
			(layer "F.SilkS")
		)
		(fp_line
			(start -0.7874 0.4064)
			(end -0.7874 -0.4064)
			(stroke
				(width 0.1524)
				(type default)
			)
			(layer "F.SilkS")
		)
		(fp_line
			(start -0.7874 -0.4064)
			(end 0.7874 -0.4064)
			(stroke
				(width 0.1524)
				(type default)
			)
			(layer "F.SilkS")
		)
		(fp_line
			(start 0.67945 0.3048)
			(end 0.120396 0.3048)
			(stroke
				(width 0.1)
				(type default)
			)
			(layer "F.Fab")
		)
		(fp_line
			(start 0.67945 -0.3048)
			(end 0.67945 0.3048)
			(stroke
				(width 0.1)
				(type default)
			)
			(layer "F.Fab")
		)
		(fp_line
			(start 0.12065 -0.2794)
			(end 0.12065 -0.3048)
			(stroke
				(width 0.1)
				(type default)
			)
			(layer "F.Fab")
		)
		(fp_line
			(start 0.12065 -0.3048)
			(end 0.67945 -0.3048)
			(stroke
				(width 0.1)
				(type default)
			)
			(layer "F.Fab")
		)
		(fp_line
			(start 0.120396 0.3048)
			(end 0.120396 0.2794)
			(stroke
				(width 0.1)
				(type default)
			)
			(layer "F.Fab")
		)
		(fp_line
			(start 0.120396 0.2794)
			(end -0.12065 0.2794)
			(stroke
				(width 0.1)
				(type default)
			)
			(layer "F.Fab")
		)
		(fp_line
			(start -0.12065 0.3048)
			(end -0.67945 0.3048)
			(stroke
				(width 0.1)
				(type default)
			)
			(layer "F.Fab")
		)
		(fp_line
			(start -0.12065 0.2794)
			(end -0.12065 0.3048)
			(stroke
				(width 0.1)
				(type default)
			)
			(layer "F.Fab")
		)
		(fp_line
			(start -0.12065 -0.2794)
			(end 0.12065 -0.2794)
			(stroke
				(width 0.1)
				(type default)
			)
			(layer "F.Fab")
		)
		(fp_line
			(start -0.12065 -0.305054)
			(end -0.12065 -0.2794)
			(stroke
				(width 0.1)
				(type default)
			)
			(layer "F.Fab")
		)
		(fp_line
			(start -0.67945 0.3048)
			(end -0.67945 -0.305054)
			(stroke
				(width 0.1)
				(type default)
			)
			(layer "F.Fab")
		)
		(fp_line
			(start -0.67945 -0.305054)
			(end -0.12065 -0.305054)
			(stroke
				(width 0.1)
				(type default)
			)
			(layer "F.Fab")
		)
		(pad "1" smd circle
			(at -0.40005 0 180)
			(size 0 0)
			(layers "F.Cu" "F.Mask" "F.Paste")
			(net "FAN_1_PRSNT_BUF_R_N")
		)
		(pad "2" smd circle
			(at 0.40005 0 180)
			(size 0 0)
			(layers "F.Cu" "F.Mask" "F.Paste")
			(net "FAN_1_PRSNT_BUF_N")
		)
	)
	(footprint ""
		(layer "F.Cu")
		(at 28.956 -169.545 180)
		(property "Reference" "R5093"
			(at 0 0 180)
			(layer "F.SilkS")
			(hide yes)
			(effects
				(font
					(size 1.27 1.27)
				)
			)
		)
		(property "Value" ""
			(at 0 0 180)
			(layer "F.Fab")
			(effects
				(font
					(size 1.27 1.27)
				)
			)
		)
		(duplicate_pad_numbers_are_jumpers no)
		(fp_line
			(start 0.7874 0.4064)
			(end -0.7874 0.4064)
			(stroke
				(width 0.1524)
				(type default)
			)
			(layer "F.SilkS")
		)
		(fp_line
			(start 0.7874 -0.4064)
			(end 0.7874 0.4064)
			(stroke
				(width 0.1524)
				(type default)
			)
			(layer "F.SilkS")
		)
		(fp_line
			(start -0.7874 0.4064)
			(end -0.7874 -0.4064)
			(stroke
				(width 0.1524)
				(type default)
			)
			(layer "F.SilkS")
		)
		(fp_line
			(start -0.7874 -0.4064)
			(end 0.7874 -0.4064)
			(stroke
				(width 0.1524)
				(type default)
			)
			(layer "F.SilkS")
		)
		(fp_line
			(start 0.67945 0.3048)
			(end 0.120396 0.3048)
			(stroke
				(width 0.1)
				(type default)
			)
			(layer "F.Fab")
		)
		(fp_line
			(start 0.67945 -0.3048)
			(end 0.67945 0.3048)
			(stroke
				(width 0.1)
				(type default)
			)
			(layer "F.Fab")
		)
		(fp_line
			(start 0.12065 -0.2794)
			(end 0.12065 -0.3048)
			(stroke
				(width 0.1)
				(type default)
			)
			(layer "F.Fab")
		)
		(fp_line
			(start 0.12065 -0.3048)
			(end 0.67945 -0.3048)
			(stroke
				(width 0.1)
				(type default)
			)
			(layer "F.Fab")
		)
		(fp_line
			(start 0.120396 0.3048)
			(end 0.120396 0.2794)
			(stroke
				(width 0.1)
				(type default)
			)
			(layer "F.Fab")
		)
		(fp_line
			(start 0.120396 0.2794)
			(end -0.12065 0.2794)
			(stroke
				(width 0.1)
				(type default)
			)
			(layer "F.Fab")
		)
		(fp_line
			(start -0.12065 0.3048)
			(end -0.67945 0.3048)
			(stroke
				(width 0.1)
				(type default)
			)
			(layer "F.Fab")
		)
		(fp_line
			(start -0.12065 0.2794)
			(end -0.12065 0.3048)
			(stroke
				(width 0.1)
				(type default)
			)
			(layer "F.Fab")
		)
		(fp_line
			(start -0.12065 -0.2794)
			(end 0.12065 -0.2794)
			(stroke
				(width 0.1)
				(type default)
			)
			(layer "F.Fab")
		)
		(fp_line
			(start -0.12065 -0.305054)
			(end -0.12065 -0.2794)
			(stroke
				(width 0.1)
				(type default)
			)
			(layer "F.Fab")
		)
		(fp_line
			(start -0.67945 0.3048)
			(end -0.67945 -0.305054)
			(stroke
				(width 0.1)
				(type default)
			)
			(layer "F.Fab")
		)
		(fp_line
			(start -0.67945 -0.305054)
			(end -0.12065 -0.305054)
			(stroke
				(width 0.1)
				(type default)
			)
			(layer "F.Fab")
		)
		(pad "1" smd circle
			(at -0.40005 0 180)
			(size 0 0)
			(layers "F.Cu" "F.Mask" "F.Paste")
			(net "PU_U8_PIN2")
		)
		(pad "2" smd circle
			(at 0.40005 0 180)
			(size 0 0)
			(layers "F.Cu" "F.Mask" "F.Paste")
			(net "P3V3_AUX")
		)
	)
	(footprint ""
		(layer "F.Cu")
		(at 34.29 -160.02 90)
		(property "Reference" "R4876"
			(at 0 0 90)
			(layer "F.SilkS")
			(hide yes)
			(effects
				(font
					(size 1.27 1.27)
				)
			)
		)
		(property "Value" ""
			(at 0 0 90)
			(layer "F.Fab")
			(effects
				(font
					(size 1.27 1.27)
				)
			)
		)
		(duplicate_pad_numbers_are_jumpers no)
		(fp_line
			(start 0.7874 -0.4064)
			(end 0.7874 0.4064)
			(stroke
				(width 0.1524)
				(type default)
			)
			(layer "F.SilkS")
		)
		(fp_line
			(start -0.7874 -0.4064)
			(end 0.7874 -0.4064)
			(stroke
				(width 0.1524)
				(type default)
			)
			(layer "F.SilkS")
		)
		(fp_line
			(start 0.7874 0.4064)
			(end -0.7874 0.4064)
			(stroke
				(width 0.1524)
				(type default)
			)
			(layer "F.SilkS")
		)
		(fp_line
			(start -0.7874 0.4064)
			(end -0.7874 -0.4064)
			(stroke
				(width 0.1524)
				(type default)
			)
			(layer "F.SilkS")
		)
		(fp_line
			(start -0.12065 -0.305054)
			(end -0.12065 -0.2794)
			(stroke
				(width 0.1)
				(type default)
			)
			(layer "F.Fab")
		)
		(fp_line
			(start -0.67945 -0.305054)
			(end -0.12065 -0.305054)
			(stroke
				(width 0.1)
				(type default)
			)
			(layer "F.Fab")
		)
		(fp_line
			(start 0.67945 -0.3048)
			(end 0.67945 0.3048)
			(stroke
				(width 0.1)
				(type default)
			)
			(layer "F.Fab")
		)
		(fp_line
			(start 0.12065 -0.3048)
			(end 0.67945 -0.3048)
			(stroke
				(width 0.1)
				(type default)
			)
			(layer "F.Fab")
		)
		(fp_line
			(start 0.12065 -0.2794)
			(end 0.12065 -0.3048)
			(stroke
				(width 0.1)
				(type default)
			)
			(layer "F.Fab")
		)
		(fp_line
			(start -0.12065 -0.2794)
			(end 0.12065 -0.2794)
			(stroke
				(width 0.1)
				(type default)
			)
			(layer "F.Fab")
		)
		(fp_line
			(start 0.120396 0.2794)
			(end -0.12065 0.2794)
			(stroke
				(width 0.1)
				(type default)
			)
			(layer "F.Fab")
		)
		(fp_line
			(start -0.12065 0.2794)
			(end -0.12065 0.3048)
			(stroke
				(width 0.1)
				(type default)
			)
			(layer "F.Fab")
		)
		(fp_line
			(start 0.67945 0.3048)
			(end 0.120396 0.3048)
			(stroke
				(width 0.1)
				(type default)
			)
			(layer "F.Fab")
		)
		(fp_line
			(start 0.120396 0.3048)
			(end 0.120396 0.2794)
			(stroke
				(width 0.1)
				(type default)
			)
			(layer "F.Fab")
		)
		(fp_line
			(start -0.12065 0.3048)
			(end -0.67945 0.3048)
			(stroke
				(width 0.1)
				(type default)
			)
			(layer "F.Fab")
		)
		(fp_line
			(start -0.67945 0.3048)
			(end -0.67945 -0.305054)
			(stroke
				(width 0.1)
				(type default)
			)
			(layer "F.Fab")
		)
		(pad "1" smd circle
			(at -0.40005 0 90)
			(size 0 0)
			(layers "F.Cu" "F.Mask" "F.Paste")
			(net "SMB_FAN4_R_SDA")
		)
		(pad "2" smd circle
			(at 0.40005 0 90)
			(size 0 0)
			(layers "F.Cu" "F.Mask" "F.Paste")
			(net "SMB_FAN4_SDA")
		)
	)
	(footprint ""
		(layer "F.Cu")
		(at 14.0589 -129.794 180)
		(property "Reference" "R5591"
			(at 0 0 180)
			(layer "F.SilkS")
			(hide yes)
			(effects
				(font
					(size 1.27 1.27)
				)
			)
		)
		(property "Value" ""
			(at 0 0 180)
			(layer "F.Fab")
			(effects
				(font
					(size 1.27 1.27)
				)
			)
		)
		(duplicate_pad_numbers_are_jumpers no)
		(fp_line
			(start 0.7874 0.4064)
			(end -0.7874 0.4064)
			(stroke
				(width 0.1524)
				(type default)
			)
			(layer "F.SilkS")
		)
		(fp_line
			(start 0.7874 -0.4064)
			(end 0.7874 0.4064)
			(stroke
				(width 0.1524)
				(type default)
			)
			(layer "F.SilkS")
		)
		(fp_line
			(start -0.7874 0.4064)
			(end -0.7874 -0.4064)
			(stroke
				(width 0.1524)
				(type default)
			)
			(layer "F.SilkS")
		)
		(fp_line
			(start -0.7874 -0.4064)
			(end 0.7874 -0.4064)
			(stroke
				(width 0.1524)
				(type default)
			)
			(layer "F.SilkS")
		)
		(fp_line
			(start 0.67945 0.3048)
			(end 0.120396 0.3048)
			(stroke
				(width 0.1)
				(type default)
			)
			(layer "F.Fab")
		)
		(fp_line
			(start 0.67945 -0.3048)
			(end 0.67945 0.3048)
			(stroke
				(width 0.1)
				(type default)
			)
			(layer "F.Fab")
		)
		(fp_line
			(start 0.12065 -0.2794)
			(end 0.12065 -0.3048)
			(stroke
				(width 0.1)
				(type default)
			)
			(layer "F.Fab")
		)
		(fp_line
			(start 0.12065 -0.3048)
			(end 0.67945 -0.3048)
			(stroke
				(width 0.1)
				(type default)
			)
			(layer "F.Fab")
		)
		(fp_line
			(start 0.120396 0.3048)
			(end 0.120396 0.2794)
			(stroke
				(width 0.1)
				(type default)
			)
			(layer "F.Fab")
		)
		(fp_line
			(start 0.120396 0.2794)
			(end -0.12065 0.2794)
			(stroke
				(width 0.1)
				(type default)
			)
			(layer "F.Fab")
		)
		(fp_line
			(start -0.12065 0.3048)
			(end -0.67945 0.3048)
			(stroke
				(width 0.1)
				(type default)
			)
			(layer "F.Fab")
		)
		(fp_line
			(start -0.12065 0.2794)
			(end -0.12065 0.3048)
			(stroke
				(width 0.1)
				(type default)
			)
			(layer "F.Fab")
		)
		(fp_line
			(start -0.12065 -0.2794)
			(end 0.12065 -0.2794)
			(stroke
				(width 0.1)
				(type default)
			)
			(layer "F.Fab")
		)
		(fp_line
			(start -0.12065 -0.305054)
			(end -0.12065 -0.2794)
			(stroke
				(width 0.1)
				(type default)
			)
			(layer "F.Fab")
		)
		(fp_line
			(start -0.67945 0.3048)
			(end -0.67945 -0.305054)
			(stroke
				(width 0.1)
				(type default)
			)
			(layer "F.Fab")
		)
		(fp_line
			(start -0.67945 -0.305054)
			(end -0.12065 -0.305054)
			(stroke
				(width 0.1)
				(type default)
			)
			(layer "F.Fab")
		)
		(pad "1" smd rect
			(at -0.40005 0)
			(size 0.4572 0.508)
			(layers "F.Cu" "F.Mask" "F.Paste")
			(net "FAN_6_PWM")
		)
		(pad "2" smd rect
			(at 0.40005 0)
			(size 0.4572 0.508)
			(layers "F.Cu" "F.Mask" "F.Paste")
			(net "FAN_6_PWM_R2")
		)
	)
	(footprint ""
		(layer "F.Cu")
		(at 22.479 -208.788 90)
		(property "Reference" "U62"
			(at 0.635 -1.87833 90)
			(unlocked yes)
			(layer "F.SilkS")
			(effects
				(font
					(size 0.7874 0.5842)
					(thickness 0.1524)
				)
				(justify left)
			)
		)
		(property "Value" ""
			(at 0 0 90)
			(layer "F.Fab")
			(effects
				(font
					(size 1.27 1.27)
				)
			)
		)
		(duplicate_pad_numbers_are_jumpers no)
		(fp_line
			(start 1.33096 -1.100074)
			(end 1.33096 1.100074)
			(stroke
				(width 0.1524)
				(type default)
			)
			(layer "F.SilkS")
		)
		(fp_line
			(start 0.381 -1.100074)
			(end 1.33096 -1.100074)
			(stroke
				(width 0.1524)
				(type default)
			)
			(layer "F.SilkS")
		)
		(fp_line
			(start -0.381 -1.100074)
			(end 0 -0.649986)
			(stroke
				(width 0.1524)
				(type default)
			)
			(layer "F.SilkS")
		)
		(fp_line
			(start -1.33096 -1.100074)
			(end -0.381 -1.100074)
			(stroke
				(width 0.1524)
				(type default)
			)
			(layer "F.SilkS")
		)
		(fp_line
			(start 0 -0.649986)
			(end 0.381 -1.100074)
			(stroke
				(width 0.1524)
				(type default)
			)
			(layer "F.SilkS")
		)
		(fp_line
			(start 1.33096 1.100074)
			(end -1.33096 1.100074)
			(stroke
				(width 0.1524)
				(type default)
			)
			(layer "F.SilkS")
		)
		(fp_line
			(start -1.33096 1.100074)
			(end -1.33096 -1.100074)
			(stroke
				(width 0.1524)
				(type default)
			)
			(layer "F.SilkS")
		)
		(fp_poly
			(pts
				(xy -0.748538 -2.082292) (xy -1.256538 -2.082292) (xy -1.002538 -1.320292)
			)
			(stroke
				(width 0)
				(type default)
			)
			(fill yes)
			(layer "F.SilkS")
		)
		(fp_line
			(start 0.674878 -1.100074)
			(end 0.674878 1.100074)
			(stroke
				(width 0.1)
				(type default)
			)
			(layer "F.Fab")
		)
		(fp_line
			(start -0.674878 -1.100074)
			(end 0.674878 -1.100074)
			(stroke
				(width 0.1)
				(type default)
			)
			(layer "F.Fab")
		)
		(fp_line
			(start 0.674878 1.100074)
			(end -0.674878 1.100074)
			(stroke
				(width 0.1)
				(type default)
			)
			(layer "F.Fab")
		)
		(fp_line
			(start -0.674878 1.100074)
			(end -0.674878 -1.100074)
			(stroke
				(width 0.1)
				(type default)
			)
			(layer "F.Fab")
		)
		(fp_poly
			(pts
				(xy -2.209292 -0.902462) (xy -2.209292 -0.394462) (xy -1.447292 -0.648462)
			)
			(stroke
				(width 0)
				(type default)
			)
			(fill yes)
			(layer "F.Fab")
		)
		(pad "1" smd rect
			(at -0.94996 -0.649986 180)
			(size 0.4064 0.508)
			(layers "F.Cu" "F.Mask" "F.Paste")
			(net "NC_U62_P1")
		)
		(pad "2" smd rect
			(at -0.94996 0 180)
			(size 0.4064 0.508)
			(layers "F.Cu" "F.Mask" "F.Paste")
			(net "FAN_1_PWM")
		)
		(pad "3" smd rect
			(at -0.94996 0.649986 180)
			(size 0.4064 0.508)
			(layers "F.Cu" "F.Mask" "F.Paste")
			(net "GND")
		)
		(pad "4" smd rect
			(at 0.94996 0.649986 180)
			(size 0.4064 0.508)
			(layers "F.Cu" "F.Mask" "F.Paste")
			(net "FAN_1_PWM_BUF")
		)
		(pad "5" smd rect
			(at 0.94996 -0.649986 180)
			(size 0.4064 0.508)
			(layers "F.Cu" "F.Mask" "F.Paste")
			(net "P3V3_AUX")
		)
	)
	(footprint ""
		(layer "F.Cu")
		(at 17.018 -20.574 180)
		(property "Reference" "R5539"
			(at 0 0 180)
			(layer "F.SilkS")
			(hide yes)
			(effects
				(font
					(size 1.27 1.27)
				)
			)
		)
		(property "Value" ""
			(at 0 0 180)
			(layer "F.Fab")
			(effects
				(font
					(size 1.27 1.27)
				)
			)
		)
		(duplicate_pad_numbers_are_jumpers no)
		(fp_line
			(start 0.7874 0.4064)
			(end -0.7874 0.4064)
			(stroke
				(width 0.1524)
				(type default)
			)
			(layer "F.SilkS")
		)
		(fp_line
			(start 0.7874 -0.4064)
			(end 0.7874 0.4064)
			(stroke
				(width 0.1524)
				(type default)
			)
			(layer "F.SilkS")
		)
		(fp_line
			(start -0.7874 0.4064)
			(end -0.7874 -0.4064)
			(stroke
				(width 0.1524)
				(type default)
			)
			(layer "F.SilkS")
		)
		(fp_line
			(start -0.7874 -0.4064)
			(end 0.7874 -0.4064)
			(stroke
				(width 0.1524)
				(type default)
			)
			(layer "F.SilkS")
		)
		(fp_line
			(start 0.67945 0.3048)
			(end 0.120396 0.3048)
			(stroke
				(width 0.1)
				(type default)
			)
			(layer "F.Fab")
		)
		(fp_line
			(start 0.67945 -0.3048)
			(end 0.67945 0.3048)
			(stroke
				(width 0.1)
				(type default)
			)
			(layer "F.Fab")
		)
		(fp_line
			(start 0.12065 -0.2794)
			(end 0.12065 -0.3048)
			(stroke
				(width 0.1)
				(type default)
			)
			(layer "F.Fab")
		)
		(fp_line
			(start 0.12065 -0.3048)
			(end 0.67945 -0.3048)
			(stroke
				(width 0.1)
				(type default)
			)
			(layer "F.Fab")
		)
		(fp_line
			(start 0.120396 0.3048)
			(end 0.120396 0.2794)
			(stroke
				(width 0.1)
				(type default)
			)
			(layer "F.Fab")
		)
		(fp_line
			(start 0.120396 0.2794)
			(end -0.12065 0.2794)
			(stroke
				(width 0.1)
				(type default)
			)
			(layer "F.Fab")
		)
		(fp_line
			(start -0.12065 0.3048)
			(end -0.67945 0.3048)
			(stroke
				(width 0.1)
				(type default)
			)
			(layer "F.Fab")
		)
		(fp_line
			(start -0.12065 0.2794)
			(end -0.12065 0.3048)
			(stroke
				(width 0.1)
				(type default)
			)
			(layer "F.Fab")
		)
		(fp_line
			(start -0.12065 -0.2794)
			(end 0.12065 -0.2794)
			(stroke
				(width 0.1)
				(type default)
			)
			(layer "F.Fab")
		)
		(fp_line
			(start -0.12065 -0.305054)
			(end -0.12065 -0.2794)
			(stroke
				(width 0.1)
				(type default)
			)
			(layer "F.Fab")
		)
		(fp_line
			(start -0.67945 0.3048)
			(end -0.67945 -0.305054)
			(stroke
				(width 0.1)
				(type default)
			)
			(layer "F.Fab")
		)
		(fp_line
			(start -0.67945 -0.305054)
			(end -0.12065 -0.305054)
			(stroke
				(width 0.1)
				(type default)
			)
			(layer "F.Fab")
		)
		(pad "1" smd rect
			(at -0.40005 0)
			(size 0.4572 0.508)
			(layers "F.Cu" "F.Mask" "F.Paste")
			(net "P12V_LED_FAN4")
		)
		(pad "2" smd rect
			(at 0.40005 0)
			(size 0.4572 0.508)
			(layers "F.Cu" "F.Mask" "F.Paste")
			(net "FAN_4_FAIL_LED_R_N")
		)
	)
)
